G04 ================== begin FILE IDENTIFICATION RECORD ==================*
G04 Layout Name:  D:/<user>/Wistron_project/16347-sc/gbr/16347-sc.brd*
G04 Film Name:    BSILK*
G04 File Format:  Gerber RS274X*
G04 File Origin:  Cadence Allegro 16.5-S056*
G04 Origin Date:  Tue Mar 14 17:08:15 2017*
G04 *
G04 Layer:  VIA CLASS/FILMMASKBOTTOM*
G04 Layer:  REF DES/ASSEMBLY_BOTTOM*
G04 Layer:  PACKAGE GEOMETRY/SILKSCREEN_BOTTOM*
G04 Layer:  DRAWING FORMAT/LAYER_PCB_STORY*
G04 Layer:  DRAWING FORMAT/LAYER_SILK_B*
G04 Layer:  BOARD GEOMETRY/SILKSCREEN_BOTTOM*
G04 *
G04 Offset:    (0.00 0.00)*
G04 Mirror:    No*
G04 Mode:      Positive*
G04 Rotation:  0*
G04 FullContactRelief:  No*
G04 UndefLineWidth:     6.00*
G04 ================== end FILE IDENTIFICATION RECORD ====================*
%FSLAX35Y35*MOIN*%
%IR0*IPPOS*OFA0.00000B0.00000*MIA0B0*SFA1.00000B1.00000*%
%ADD10C,.02*%
%ADD11C,.013*%
%ADD12C,.015*%
%ADD13C,.006*%
%ADD14C,.008*%
G75*
%LPD*%
G75*
G36*
G01X211221Y63150D02*
X208721Y65650D01*
X213721D01*
X211221Y63150D01*
G37*
G36*
G01X212421Y38592D02*
X174587D01*
Y55108D01*
X212421D01*
Y38592D01*
G37*
G54D10*
G01X-23515Y-108314D02*
X-55515D01*
G01X-23515Y-124314D02*
Y-204314D01*
G01D02*
X1177585D01*
G01X-27515Y-108314D02*
G02I-12000J0D01*
G01X-39515Y-124314D02*
Y-92314D01*
G01X-23515Y-124314D02*
X1177585D01*
G01X-23515Y-159814D02*
X1177585D01*
G01X-32665Y-108314D02*
G02I-6850J0D01*
G01X390085Y-124314D02*
Y-204314D01*
G01X527585Y-124314D02*
Y-204314D01*
G01X642585Y-124314D02*
Y-204314D01*
G01X810085Y-124314D02*
Y-204314D01*
G01X980085Y-124314D02*
Y-204314D01*
G01X1177585Y-124314D02*
Y-204314D01*
G01X1205585Y-108314D02*
G02I-12000J0D01*
G01X1200435D02*
G02I-6850J0D01*
G01X1209585D02*
X1177585D01*
G01X1193585Y-124314D02*
Y-92314D01*
G54D11*
G01X209404Y63200D02*
X213754D01*
Y59400D01*
G54D12*
G01X4724Y39370D02*
X29921D01*
G01X4724Y130709D02*
X29921D01*
G01X4724Y174016D02*
X29921D01*
G01X4724Y265355D02*
X29921D01*
G01X4724Y308662D02*
X29921D01*
G01X4724Y400001D02*
X29921D01*
G01Y443308D02*
X4724D01*
G01X29921Y534647D02*
X4724D01*
G01Y577954D02*
X29921D01*
G01Y669293D02*
X4724D01*
G01X29921Y712600D02*
X4724D01*
G01X29921Y803939D02*
X4724D01*
G01Y847246D02*
X29921D01*
G01X72639Y113780D02*
Y88583D01*
G01Y248426D02*
Y223229D01*
G01Y383072D02*
Y357875D01*
G01Y517718D02*
Y492521D01*
G01Y652364D02*
Y627167D01*
G01Y787010D02*
Y761813D01*
G01Y921656D02*
Y896459D01*
G01X206102Y71654D02*
X180905D01*
G01X206102Y79528D02*
X180905D01*
G01X206102Y206300D02*
X180905D01*
G01X206102Y214174D02*
X180905D01*
G01X206102Y340946D02*
X180905D01*
G01X206102Y348820D02*
X180905D01*
G01X206102Y475592D02*
X180905D01*
G01X206102Y483466D02*
X180905D01*
G01Y610238D02*
X206102D01*
G01X180905Y618112D02*
X206102D01*
G01X180905Y744884D02*
X206102D01*
G01X180905Y752758D02*
X206102D01*
G01X180905Y879530D02*
X206102D01*
G01X180905Y887404D02*
X206102D01*
G01X196309Y122835D02*
X221506D01*
G01X196309Y130709D02*
X221506D01*
G01X196309Y257481D02*
X221506D01*
G01X196309Y265355D02*
X221506D01*
G01X196309Y392127D02*
X221506D01*
G01X196309Y400001D02*
X221506D01*
G01X196309Y526773D02*
X221506D01*
G01X196309Y534647D02*
X221506D01*
G01X196309Y661419D02*
X221506D01*
G01X196309Y669293D02*
X221506D01*
G01X196309Y796065D02*
X221506D01*
G01X196309Y803939D02*
X221506D01*
G01X325788Y39370D02*
X350985D01*
G01Y79528D02*
X325788D01*
G01Y174016D02*
X350985D01*
G01X325788Y214174D02*
X350985D01*
G01X325788Y308662D02*
X350985D01*
G01X325788Y348820D02*
X350985D01*
G01X325788Y443308D02*
X350985D01*
G01X325788Y483466D02*
X350985D01*
G01X325788Y577954D02*
X350985D01*
G01X325788Y618112D02*
X350985D01*
G01Y712600D02*
X325788D01*
G01Y752758D02*
X350985D01*
G01X325788Y847246D02*
X350985D01*
G01X325788Y887404D02*
X350985D01*
G01X413091Y122835D02*
X387894D01*
G01X413091Y130709D02*
X387894D01*
G01X413091Y257481D02*
X387894D01*
G01X413091Y265355D02*
X387894D01*
G01Y392127D02*
X413091D01*
G01X387894Y400001D02*
X413091D01*
G01X387894Y526773D02*
X413091D01*
G01X387894Y534647D02*
X413091D01*
G01Y661419D02*
X387894D01*
G01X413091Y669293D02*
X387894D01*
G01Y796065D02*
X413091D01*
G01X387894Y803939D02*
X413091D01*
G01X475197Y39370D02*
X450000D01*
G01X475197Y79528D02*
X450000D01*
G01Y214174D02*
X475197D01*
G01X450000Y174016D02*
X475197D01*
G01X450000Y308662D02*
X475197D01*
G01X450000Y348820D02*
X475197D01*
G01X450000Y443308D02*
X475197D01*
G01X450000Y483466D02*
X475197D01*
G01Y577954D02*
X450000D01*
G01X475197Y618112D02*
X450000D01*
G01X475197Y712600D02*
X450000D01*
G01Y752758D02*
X475197D01*
G01Y847246D02*
X450000D01*
G01X475197Y887404D02*
X450000D01*
G01X620080Y39370D02*
X594883D01*
G01X620080Y47244D02*
X594883D01*
G01X579479Y122835D02*
X604676D01*
G01X579479Y130709D02*
X604676D01*
G01X594883Y174016D02*
X620080D01*
G01X594883Y181890D02*
X620080D01*
G01X579479Y257481D02*
X604676D01*
G01X620080Y308662D02*
X594883D01*
G01X579479Y265355D02*
X604676D01*
G01X620080Y316536D02*
X594883D01*
G01X604676Y392127D02*
X579479D01*
G01X604676Y400001D02*
X579479D01*
G01X620080Y443308D02*
X594883D01*
G01X620080Y451182D02*
X594883D01*
G01X579479Y526773D02*
X604676D01*
G01X579479Y534647D02*
X604676D01*
G01X594883Y585828D02*
X620080D01*
G01Y577954D02*
X594883D01*
G01X604676Y661419D02*
X579479D01*
G01X604676Y669293D02*
X579479D01*
G01X594883Y712600D02*
X620080D01*
G01X594883Y720474D02*
X620080D01*
G01X604676Y796065D02*
X579479D01*
G01X604676Y803939D02*
X579479D01*
G01X620080Y847246D02*
X594883D01*
G01X620080Y855120D02*
X594883D01*
G01X720079Y39370D02*
X701969D01*
G01Y79528D02*
X720079D01*
G01Y214174D02*
X701969D01*
G01Y174016D02*
X720079D01*
G01Y308662D02*
X701969D01*
G01Y348820D02*
X720079D01*
G01X701969Y443308D02*
X720079D01*
G01X701969Y483466D02*
X720079D01*
G01X701969Y577954D02*
X720079D01*
G01X701969Y618112D02*
X720079D01*
G01X701969Y712600D02*
X720079D01*
G01Y752758D02*
X701969D01*
G01Y847246D02*
X720079D01*
G01X701969Y887404D02*
X720079D01*
G01X728346Y5118D02*
Y30315D01*
G01Y139764D02*
Y164961D01*
G01Y299607D02*
Y274410D01*
G01Y434253D02*
Y409056D01*
G01Y568899D02*
Y543702D01*
G01Y703545D02*
Y678348D01*
G01Y838191D02*
Y812995D01*
G01X771064Y79528D02*
X796261D01*
G01X771064Y122835D02*
X796261D01*
G01X771064Y214174D02*
X796261D01*
G01X771064Y257481D02*
X796261D01*
G01X771064Y348820D02*
X796261D01*
G01X771064Y392127D02*
X796261D01*
G01X771064Y483466D02*
X796261D01*
G01X771064Y526773D02*
X796261D01*
G01Y618112D02*
X771064D01*
G01Y661419D02*
X796261D01*
G01X771064Y752758D02*
X796261D01*
G01X771064Y796065D02*
X796261D01*
G01Y887404D02*
X771064D01*
G54D13*
G01X981Y-184981D02*
X1855Y-184106D01*
X2510Y-182648D01*
X2947Y-180605D01*
X2510Y-178856D01*
X1637Y-177689D01*
X108Y-176814D01*
X-5787D01*
Y-194314D01*
X1418D01*
X2947Y-193148D01*
X3820Y-191397D01*
X4257Y-189356D01*
X3820Y-187314D01*
X2510Y-185564D01*
X981Y-184981D01*
X-5787D01*
G01X13678Y-194314D02*
Y-182648D01*
G01Y-184981D02*
X14770Y-183814D01*
X15862Y-182939D01*
X17390Y-182648D01*
X18481Y-182939D01*
X19792Y-183814D01*
G01X29650Y-199564D02*
X30960Y-200147D01*
X32707Y-199564D01*
X33798Y-198398D01*
X34672Y-196939D01*
X35981Y-192273D01*
X38820Y-182648D01*
G01X31833D02*
X35981Y-192273D01*
G01X55228Y-184106D02*
X53700Y-182939D01*
X52390Y-182648D01*
X50643Y-183231D01*
X49333Y-184397D01*
X48460Y-186439D01*
X48241Y-188481D01*
X48460Y-190523D01*
X49333Y-192273D01*
X50643Y-193731D01*
X52390Y-194314D01*
X53918Y-193731D01*
X55228Y-192564D01*
G01X65960Y-186439D02*
X72947D01*
X72292Y-184397D01*
X71200Y-183231D01*
X69672Y-182648D01*
X68143Y-182939D01*
X66833Y-183814D01*
X65960Y-185856D01*
X65523Y-187606D01*
Y-189356D01*
X65960Y-191106D01*
X67052Y-192856D01*
X68362Y-194022D01*
X69890Y-194314D01*
X71418Y-193731D01*
X72947Y-191981D01*
G01X109038Y-178273D02*
X107728Y-177397D01*
X106200Y-176814D01*
X104453D01*
X102488Y-177689D01*
X100960Y-179147D01*
X99868Y-180898D01*
X98995Y-183814D01*
X98776Y-186439D01*
X99213Y-189064D01*
X99868Y-190814D01*
X101178Y-192564D01*
X102707Y-193731D01*
X104235Y-194314D01*
X105763D01*
X107292Y-193731D01*
X108602Y-192856D01*
X109694Y-191690D01*
G01X125665Y-194314D02*
Y-182648D01*
G01Y-184689D02*
X124792Y-183523D01*
X123481Y-182939D01*
X121953Y-182648D01*
X120425Y-183231D01*
X119115Y-184397D01*
X118241Y-186147D01*
X117805Y-188481D01*
X118241Y-190814D01*
X119115Y-192564D01*
X120425Y-193731D01*
X121953Y-194314D01*
X123481Y-194022D01*
X124792Y-193148D01*
X125665Y-191981D01*
G01X135523Y-194314D02*
Y-182648D01*
G01Y-185564D02*
X136397Y-184106D01*
X137707Y-182939D01*
X139453Y-182648D01*
X140981Y-182939D01*
X142292Y-184106D01*
X142947Y-186147D01*
Y-194314D01*
G01X152150Y-199564D02*
X153460Y-200147D01*
X155207Y-199564D01*
X156298Y-198398D01*
X157172Y-196939D01*
X158481Y-192273D01*
X161320Y-182648D01*
G01X154333D02*
X158481Y-192273D01*
G01X174235Y-194314D02*
X172925Y-194022D01*
X171615Y-192856D01*
X170741Y-190814D01*
X170305Y-188481D01*
X170741Y-186147D01*
X171615Y-184106D01*
X172925Y-182939D01*
X174235Y-182648D01*
X175545Y-182939D01*
X176855Y-184106D01*
X177728Y-186147D01*
X177947Y-188481D01*
X177728Y-190814D01*
X176855Y-192856D01*
X175545Y-194022D01*
X174235Y-194314D01*
G01X188023D02*
Y-182648D01*
G01Y-185564D02*
X188897Y-184106D01*
X190207Y-182939D01*
X191953Y-182648D01*
X193481Y-182939D01*
X194792Y-184106D01*
X195447Y-186147D01*
Y-194314D01*
G01X222368Y-176814D02*
Y-194314D01*
X231102D01*
G01X248602D02*
X239868D01*
Y-176814D01*
X248602D01*
G01X245108Y-185272D02*
X239868D01*
G01X256932Y-194314D02*
Y-176814D01*
X261298D01*
X263045Y-177689D01*
X264355Y-178856D01*
X265447Y-180605D01*
X266320Y-182648D01*
X266538Y-185564D01*
X266320Y-188481D01*
X265447Y-190523D01*
X264355Y-192273D01*
X263045Y-193439D01*
X261298Y-194314D01*
X256932D01*
G01X298481Y-184981D02*
X299355Y-184106D01*
X300010Y-182648D01*
X300447Y-180605D01*
X300010Y-178856D01*
X299137Y-177689D01*
X297608Y-176814D01*
X291713D01*
Y-194314D01*
X298918D01*
X300447Y-193148D01*
X301320Y-191397D01*
X301757Y-189356D01*
X301320Y-187314D01*
X300010Y-185564D01*
X298481Y-184981D01*
X291713D01*
G01X314235Y-194314D02*
X312925Y-194022D01*
X311615Y-192856D01*
X310741Y-190814D01*
X310305Y-188481D01*
X310741Y-186147D01*
X311615Y-184106D01*
X312925Y-182939D01*
X314235Y-182648D01*
X315545Y-182939D01*
X316855Y-184106D01*
X317728Y-186147D01*
X317947Y-188481D01*
X317728Y-190814D01*
X316855Y-192856D01*
X315545Y-194022D01*
X314235Y-194314D01*
G01X335665D02*
Y-182648D01*
G01Y-184689D02*
X334792Y-183523D01*
X333481Y-182939D01*
X331953Y-182648D01*
X330425Y-183231D01*
X329115Y-184397D01*
X328241Y-186147D01*
X327805Y-188481D01*
X328241Y-190814D01*
X329115Y-192564D01*
X330425Y-193731D01*
X331953Y-194314D01*
X333481Y-194022D01*
X334792Y-193148D01*
X335665Y-191981D01*
G01X346178Y-194314D02*
Y-182648D01*
G01Y-184981D02*
X347270Y-183814D01*
X348362Y-182939D01*
X349890Y-182648D01*
X350981Y-182939D01*
X352292Y-183814D01*
G01X370665Y-176814D02*
Y-194314D01*
G01Y-191690D02*
X369792Y-193148D01*
X368481Y-194022D01*
X366953Y-194314D01*
X365207Y-193731D01*
X363897Y-192273D01*
X363023Y-190523D01*
X362805Y-188481D01*
X363023Y-186439D01*
X363897Y-184689D01*
X365207Y-183231D01*
X366953Y-182648D01*
X368481Y-182939D01*
X369573Y-183523D01*
X370665Y-184689D01*
G01X142308Y-149314D02*
Y-131814D01*
X147985Y-146397D01*
X153662Y-131814D01*
Y-149314D01*
G01X165485D02*
X164175Y-149022D01*
X162865Y-147856D01*
X161991Y-145814D01*
X161555Y-143481D01*
X161991Y-141147D01*
X162865Y-139106D01*
X164175Y-137939D01*
X165485Y-137648D01*
X166795Y-137939D01*
X168105Y-139106D01*
X168978Y-141147D01*
X169197Y-143481D01*
X168978Y-145814D01*
X168105Y-147856D01*
X166795Y-149022D01*
X165485Y-149314D01*
G01X186915Y-131814D02*
Y-149314D01*
G01Y-146690D02*
X186042Y-148148D01*
X184731Y-149022D01*
X183203Y-149314D01*
X181457Y-148731D01*
X180147Y-147273D01*
X179273Y-145523D01*
X179055Y-143481D01*
X179273Y-141439D01*
X180147Y-139689D01*
X181457Y-138231D01*
X183203Y-137648D01*
X184731Y-137939D01*
X185823Y-138523D01*
X186915Y-139689D01*
G01X197210Y-141439D02*
X204197D01*
X203542Y-139397D01*
X202450Y-138231D01*
X200922Y-137648D01*
X199393Y-137939D01*
X198083Y-138814D01*
X197210Y-140856D01*
X196773Y-142606D01*
Y-144356D01*
X197210Y-146106D01*
X198302Y-147856D01*
X199612Y-149022D01*
X201140Y-149314D01*
X202668Y-148731D01*
X204197Y-146981D01*
G01X217985Y-149314D02*
Y-131814D01*
G01X423785Y-194314D02*
Y-176814D01*
X421165Y-180314D01*
G01Y-194314D02*
X426405D01*
G01X437137Y-187023D02*
X438665Y-184981D01*
X439975Y-183814D01*
X441722Y-183231D01*
X443250Y-183814D01*
X444342Y-184981D01*
X445215Y-186731D01*
X445433Y-188772D01*
X445215Y-190523D01*
X444342Y-192273D01*
X443031Y-193731D01*
X441503Y-194314D01*
X439757Y-193731D01*
X438228Y-191981D01*
X437355Y-189356D01*
X437137Y-186439D01*
X437573Y-182648D01*
X438228Y-180605D01*
X439320Y-178564D01*
X440848Y-177106D01*
X442377Y-176814D01*
X443905Y-177397D01*
X444997Y-178856D01*
G01X453982Y-190814D02*
X455291Y-192856D01*
X457038Y-194022D01*
X459003Y-194314D01*
X460750Y-194022D01*
X462497Y-192564D01*
X463588Y-190814D01*
X463807Y-189064D01*
X463370Y-187023D01*
X461842Y-185564D01*
X460313Y-184981D01*
X458348D01*
G01X460313D02*
X461623Y-184106D01*
X462715Y-182648D01*
X463152Y-180898D01*
X462715Y-179147D01*
X461623Y-177689D01*
X459658Y-176814D01*
X457693Y-177106D01*
X455728Y-178273D01*
G01X478905Y-194314D02*
Y-176814D01*
X470826Y-189356D01*
X481744D01*
G01X493348Y-194314D02*
X493785Y-190523D01*
X494440Y-187314D01*
X495313Y-184397D01*
X496405Y-181189D01*
X498152Y-176814D01*
X489418D01*
G01X410668Y-149314D02*
Y-131814D01*
X415908D01*
X417655Y-132689D01*
X418965Y-134731D01*
X419402Y-137064D01*
X418965Y-139397D01*
X417873Y-141147D01*
X415908Y-142023D01*
X410668D01*
G01X437338Y-133273D02*
X436028Y-132397D01*
X434500Y-131814D01*
X432753D01*
X430788Y-132689D01*
X429260Y-134147D01*
X428168Y-135898D01*
X427295Y-138814D01*
X427076Y-141439D01*
X427513Y-144064D01*
X428168Y-145814D01*
X429478Y-147564D01*
X431007Y-148731D01*
X432535Y-149314D01*
X434063D01*
X435592Y-148731D01*
X436902Y-147856D01*
X437994Y-146690D01*
G01X451781Y-139981D02*
X452655Y-139106D01*
X453310Y-137648D01*
X453747Y-135605D01*
X453310Y-133856D01*
X452437Y-132689D01*
X450908Y-131814D01*
X445013D01*
Y-149314D01*
X452218D01*
X453747Y-148148D01*
X454620Y-146397D01*
X455057Y-144356D01*
X454620Y-142314D01*
X453310Y-140564D01*
X451781Y-139981D01*
X445013D01*
G01X460985Y-155147D02*
X474085D01*
G01X480013Y-149314D02*
Y-131814D01*
X490057Y-149314D01*
Y-131814D01*
G01X502535Y-149314D02*
X500788Y-149022D01*
X499260Y-147856D01*
X497950Y-146106D01*
X497076Y-144064D01*
X496640Y-141731D01*
Y-139397D01*
X497076Y-137064D01*
X497950Y-135022D01*
X499260Y-133273D01*
X500788Y-132106D01*
X502535Y-131814D01*
X504281Y-132106D01*
X505810Y-133273D01*
X507120Y-135022D01*
X507994Y-137064D01*
X508430Y-139397D01*
Y-141731D01*
X507994Y-144064D01*
X507120Y-146106D01*
X505810Y-147856D01*
X504281Y-149022D01*
X502535Y-149314D01*
G01X553376Y-131814D02*
X558835Y-149314D01*
X564294Y-131814D01*
G01X580702Y-149314D02*
X571968D01*
Y-131814D01*
X580702D01*
G01X577208Y-140272D02*
X571968D01*
G01X589468Y-149314D02*
Y-131814D01*
X594927D01*
X596673Y-132689D01*
X597765Y-133856D01*
X598202Y-136189D01*
X597765Y-138523D01*
X596455Y-139981D01*
X594927Y-140856D01*
X589468D01*
G01X594927D02*
X598202Y-149314D01*
G01X611335Y-149897D02*
X610898Y-149606D01*
Y-149022D01*
X611335Y-148731D01*
X611772Y-149022D01*
Y-149606D01*
X611335Y-149897D01*
G01X571750Y-191981D02*
X573497Y-193439D01*
X575462Y-194314D01*
X577208D01*
X578955Y-193439D01*
X580265Y-191981D01*
X580920Y-189939D01*
X580483Y-187898D01*
X579392Y-186147D01*
X577427Y-184981D01*
X574807Y-184397D01*
X573278Y-183231D01*
X572623Y-181189D01*
X573060Y-179147D01*
X574152Y-177689D01*
X575680Y-176814D01*
X577208D01*
X578737Y-177397D01*
X580047Y-178856D01*
G01X598638Y-178273D02*
X597328Y-177397D01*
X595800Y-176814D01*
X594053D01*
X592088Y-177689D01*
X590560Y-179147D01*
X589468Y-180898D01*
X588595Y-183814D01*
X588376Y-186439D01*
X588813Y-189064D01*
X589468Y-190814D01*
X590778Y-192564D01*
X592307Y-193731D01*
X593835Y-194314D01*
X595363D01*
X596892Y-193731D01*
X598202Y-192856D01*
X599294Y-191690D01*
G01X759539Y-184981D02*
X758665Y-184106D01*
X758010Y-182648D01*
X757573Y-180605D01*
X758010Y-178856D01*
X758883Y-177689D01*
X760412Y-176814D01*
X766307D01*
Y-194314D01*
X759102D01*
X757573Y-193148D01*
X756700Y-191397D01*
X756263Y-189356D01*
X756700Y-187314D01*
X758010Y-185564D01*
X759539Y-184981D01*
X766307D01*
G01X748370Y-191981D02*
X746623Y-193439D01*
X744658Y-194314D01*
X742912D01*
X741165Y-193439D01*
X739855Y-191981D01*
X739200Y-189939D01*
X739637Y-187898D01*
X740728Y-186147D01*
X742693Y-184981D01*
X745313Y-184397D01*
X746842Y-183231D01*
X747497Y-181189D01*
X747060Y-179147D01*
X745968Y-177689D01*
X744440Y-176814D01*
X742912D01*
X741383Y-177397D01*
X740073Y-178856D01*
G01X728905Y-176814D02*
X723665D01*
G01X726285D02*
Y-194314D01*
G01X728905D02*
X723665D01*
G01X713152Y-176814D02*
Y-194314D01*
X704418D01*
G01X696088D02*
Y-176814D01*
G01X687792D02*
X696088Y-187606D01*
G01X686482Y-194314D02*
X692377Y-182648D01*
G01X686918Y-131814D02*
Y-149314D01*
X695652D01*
G01X712715D02*
Y-137648D01*
G01Y-139689D02*
X711842Y-138523D01*
X710531Y-137939D01*
X709003Y-137648D01*
X707475Y-138231D01*
X706165Y-139397D01*
X705291Y-141147D01*
X704855Y-143481D01*
X705291Y-145814D01*
X706165Y-147564D01*
X707475Y-148731D01*
X709003Y-149314D01*
X710531Y-149022D01*
X711842Y-148148D01*
X712715Y-146981D01*
G01X721700Y-154564D02*
X723010Y-155147D01*
X724757Y-154564D01*
X725848Y-153398D01*
X726722Y-151939D01*
X728031Y-147273D01*
X730870Y-137648D01*
G01X723883D02*
X728031Y-147273D01*
G01X740510Y-141439D02*
X747497D01*
X746842Y-139397D01*
X745750Y-138231D01*
X744222Y-137648D01*
X742693Y-137939D01*
X741383Y-138814D01*
X740510Y-140856D01*
X740073Y-142606D01*
Y-144356D01*
X740510Y-146106D01*
X741602Y-147856D01*
X742912Y-149022D01*
X744440Y-149314D01*
X745968Y-148731D01*
X747497Y-146981D01*
G01X758228Y-149314D02*
Y-137648D01*
G01Y-139981D02*
X759320Y-138814D01*
X760412Y-137939D01*
X761940Y-137648D01*
X763031Y-137939D01*
X764342Y-138814D01*
G01X851335Y-194314D02*
X849588Y-194022D01*
X848060Y-192856D01*
X846750Y-191106D01*
X845876Y-189064D01*
X845440Y-186731D01*
Y-184397D01*
X845876Y-182064D01*
X846750Y-180022D01*
X848060Y-178273D01*
X849588Y-177106D01*
X851335Y-176814D01*
X853081Y-177106D01*
X854610Y-178273D01*
X855920Y-180022D01*
X856794Y-182064D01*
X857230Y-184397D01*
Y-186731D01*
X856794Y-189064D01*
X855920Y-191106D01*
X854610Y-192856D01*
X853081Y-194022D01*
X851335Y-194314D01*
G01X853081Y-189647D02*
X855702Y-194314D01*
G01X864032Y-176814D02*
Y-189356D01*
X864905Y-191981D01*
X866652Y-193731D01*
X868835Y-194314D01*
X871018Y-193731D01*
X872765Y-191981D01*
X873638Y-189356D01*
Y-176814D01*
G01X883715D02*
X888955D01*
G01X886335D02*
Y-194314D01*
G01X883715D02*
X888955D01*
G01X898813D02*
Y-176814D01*
X908857Y-194314D01*
Y-176814D01*
G01X926138Y-178273D02*
X924828Y-177397D01*
X923300Y-176814D01*
X921553D01*
X919588Y-177689D01*
X918060Y-179147D01*
X916968Y-180898D01*
X916095Y-183814D01*
X915876Y-186439D01*
X916313Y-189064D01*
X916968Y-190814D01*
X918278Y-192564D01*
X919807Y-193731D01*
X921335Y-194314D01*
X922863D01*
X924392Y-193731D01*
X925702Y-192856D01*
X926794Y-191690D01*
G01X938835Y-194314D02*
Y-186439D01*
X934468Y-176814D01*
G01X943202D02*
X938835Y-186439D01*
G01X829032Y-149314D02*
Y-131814D01*
X833398D01*
X835145Y-132689D01*
X836455Y-133856D01*
X837547Y-135605D01*
X838420Y-137648D01*
X838638Y-140564D01*
X838420Y-143481D01*
X837547Y-145523D01*
X836455Y-147273D01*
X835145Y-148439D01*
X833398Y-149314D01*
X829032D01*
G01X848060Y-141439D02*
X855047D01*
X854392Y-139397D01*
X853300Y-138231D01*
X851772Y-137648D01*
X850243Y-137939D01*
X848933Y-138814D01*
X848060Y-140856D01*
X847623Y-142606D01*
Y-144356D01*
X848060Y-146106D01*
X849152Y-147856D01*
X850462Y-149022D01*
X851990Y-149314D01*
X853518Y-148731D01*
X855047Y-146981D01*
G01X865560Y-147273D02*
X866652Y-148439D01*
X868180Y-149314D01*
X869490D01*
X870800Y-148731D01*
X871673Y-147856D01*
X872110Y-146690D01*
X871892Y-144939D01*
X871018Y-144064D01*
X867088Y-142314D01*
X866215Y-140272D01*
X866652Y-138814D01*
X867525Y-137939D01*
X868835Y-137648D01*
X870145Y-137939D01*
X871455Y-138814D01*
G01X886335Y-137648D02*
Y-149314D01*
G01Y-132981D02*
X885898Y-132689D01*
Y-132106D01*
X886335Y-131814D01*
X886772Y-132106D01*
Y-132689D01*
X886335Y-132981D01*
G01X900778Y-153689D02*
X902307Y-154856D01*
X904053Y-155147D01*
X905581Y-154856D01*
X906892Y-153398D01*
X907765Y-151356D01*
Y-137648D01*
G01Y-139981D02*
X906892Y-138814D01*
X905581Y-137939D01*
X904053Y-137648D01*
X902307Y-138231D01*
X901215Y-139397D01*
X900341Y-141439D01*
X899905Y-143481D01*
X900123Y-145231D01*
X900997Y-147273D01*
X902307Y-148731D01*
X904053Y-149314D01*
X905363Y-149022D01*
X906892Y-147856D01*
X907765Y-146690D01*
G01X917623Y-149314D02*
Y-137648D01*
G01Y-140564D02*
X918497Y-139106D01*
X919807Y-137939D01*
X921553Y-137648D01*
X923081Y-137939D01*
X924392Y-139106D01*
X925047Y-141147D01*
Y-149314D01*
G01X935560Y-141439D02*
X942547D01*
X941892Y-139397D01*
X940800Y-138231D01*
X939272Y-137648D01*
X937743Y-137939D01*
X936433Y-138814D01*
X935560Y-140856D01*
X935123Y-142606D01*
Y-144356D01*
X935560Y-146106D01*
X936652Y-147856D01*
X937962Y-149022D01*
X939490Y-149314D01*
X941018Y-148731D01*
X942547Y-146981D01*
G01X953278Y-149314D02*
Y-137648D01*
G01Y-139981D02*
X954370Y-138814D01*
X955462Y-137939D01*
X956990Y-137648D01*
X958081Y-137939D01*
X959392Y-138814D01*
G01X1000035Y-176814D02*
X998288Y-177397D01*
X996978Y-178856D01*
X996105Y-180605D01*
X995450Y-182939D01*
X995232Y-185564D01*
X995450Y-188189D01*
X996105Y-190523D01*
X996978Y-192273D01*
X998288Y-193731D01*
X1000035Y-194314D01*
X1001781Y-193731D01*
X1003092Y-192273D01*
X1003965Y-190523D01*
X1004620Y-188189D01*
X1004838Y-185564D01*
X1004620Y-182939D01*
X1003965Y-180605D01*
X1003092Y-178856D01*
X1001781Y-177397D01*
X1000035Y-176814D01*
G01X1012732Y-190814D02*
X1014041Y-192856D01*
X1015788Y-194022D01*
X1017753Y-194314D01*
X1019500Y-194022D01*
X1021247Y-192564D01*
X1022338Y-190814D01*
X1022557Y-189064D01*
X1022120Y-187023D01*
X1020592Y-185564D01*
X1019063Y-184981D01*
X1017098D01*
G01X1019063D02*
X1020373Y-184106D01*
X1021465Y-182648D01*
X1021902Y-180898D01*
X1021465Y-179147D01*
X1020373Y-177689D01*
X1018408Y-176814D01*
X1016443Y-177106D01*
X1014478Y-178273D01*
G01X1031105Y-194897D02*
X1038965Y-176814D01*
G01X1052535Y-194314D02*
Y-176814D01*
X1049915Y-180314D01*
G01Y-194314D02*
X1055155D01*
G01X1065232Y-190814D02*
X1066541Y-192856D01*
X1068288Y-194022D01*
X1070253Y-194314D01*
X1072000Y-194022D01*
X1073747Y-192564D01*
X1074838Y-190814D01*
X1075057Y-189064D01*
X1074620Y-187023D01*
X1073092Y-185564D01*
X1071563Y-184981D01*
X1069598D01*
G01X1071563D02*
X1072873Y-184106D01*
X1073965Y-182648D01*
X1074402Y-180898D01*
X1073965Y-179147D01*
X1072873Y-177689D01*
X1070908Y-176814D01*
X1068943Y-177106D01*
X1066978Y-178273D01*
G01X1083605Y-194897D02*
X1091465Y-176814D01*
G01X1100887Y-179731D02*
X1102197Y-177981D01*
X1103725Y-177106D01*
X1105472Y-176814D01*
X1107655Y-177397D01*
X1109183Y-178856D01*
X1109620Y-180605D01*
X1109402Y-182356D01*
X1108528Y-183814D01*
X1104162Y-186731D01*
X1102197Y-188772D01*
X1100887Y-191690D01*
X1100450Y-194314D01*
X1109620D01*
G01X1122535Y-176814D02*
X1120788Y-177397D01*
X1119478Y-178856D01*
X1118605Y-180605D01*
X1117950Y-182939D01*
X1117732Y-185564D01*
X1117950Y-188189D01*
X1118605Y-190523D01*
X1119478Y-192273D01*
X1120788Y-193731D01*
X1122535Y-194314D01*
X1124281Y-193731D01*
X1125592Y-192273D01*
X1126465Y-190523D01*
X1127120Y-188189D01*
X1127338Y-185564D01*
X1127120Y-182939D01*
X1126465Y-180605D01*
X1125592Y-178856D01*
X1124281Y-177397D01*
X1122535Y-176814D01*
G01X1140035Y-194314D02*
Y-176814D01*
X1137415Y-180314D01*
G01Y-194314D02*
X1142655D01*
G01X1157098D02*
X1157535Y-190523D01*
X1158190Y-187314D01*
X1159063Y-184397D01*
X1160155Y-181189D01*
X1161902Y-176814D01*
X1153168D01*
G01X1047732Y-149314D02*
Y-131814D01*
X1052098D01*
X1053845Y-132689D01*
X1055155Y-133856D01*
X1056247Y-135605D01*
X1057120Y-137648D01*
X1057338Y-140564D01*
X1057120Y-143481D01*
X1056247Y-145523D01*
X1055155Y-147273D01*
X1053845Y-148439D01*
X1052098Y-149314D01*
X1047732D01*
G01X1073965D02*
Y-137648D01*
G01Y-139689D02*
X1073092Y-138523D01*
X1071781Y-137939D01*
X1070253Y-137648D01*
X1068725Y-138231D01*
X1067415Y-139397D01*
X1066541Y-141147D01*
X1066105Y-143481D01*
X1066541Y-145814D01*
X1067415Y-147564D01*
X1068725Y-148731D01*
X1070253Y-149314D01*
X1071781Y-149022D01*
X1073092Y-148148D01*
X1073965Y-146981D01*
G01X1087535Y-131814D02*
Y-149314D01*
G01X1084478Y-137648D02*
X1090592D01*
G01X1101760Y-141439D02*
X1108747D01*
X1108092Y-139397D01*
X1107000Y-138231D01*
X1105472Y-137648D01*
X1103943Y-137939D01*
X1102633Y-138814D01*
X1101760Y-140856D01*
X1101323Y-142606D01*
Y-144356D01*
X1101760Y-146106D01*
X1102852Y-147856D01*
X1104162Y-149022D01*
X1105690Y-149314D01*
X1107218Y-148731D01*
X1108747Y-146981D01*
G01X80433Y5500D02*
Y8000D01*
X79392D01*
X79058Y7875D01*
X78850Y7708D01*
X78767Y7375D01*
X78850Y7042D01*
X79100Y6833D01*
X79392Y6708D01*
X80433D01*
G01X79392D02*
X78767Y5500D01*
G01X76500D02*
Y8000D01*
X77000Y7500D01*
G01Y5500D02*
X76000D01*
G01X74317Y6000D02*
X74067Y5708D01*
X73733Y5542D01*
X73358Y5500D01*
X73025Y5542D01*
X72692Y5750D01*
X72483Y6000D01*
X72442Y6250D01*
X72525Y6542D01*
X72817Y6750D01*
X73108Y6833D01*
X73483D01*
G01X73108D02*
X72858Y6958D01*
X72650Y7167D01*
X72567Y7417D01*
X72650Y7667D01*
X72858Y7875D01*
X73233Y8000D01*
X73608Y7958D01*
X73983Y7792D01*
G01X79900Y13400D02*
Y9400D01*
X72500D01*
G01X94433Y6500D02*
Y9000D01*
X93392D01*
X93058Y8875D01*
X92850Y8708D01*
X92767Y8375D01*
X92850Y8042D01*
X93100Y7833D01*
X93392Y7708D01*
X94433D01*
G01X93392D02*
X92767Y6500D01*
G01X90500D02*
Y9000D01*
X91000Y8500D01*
G01Y6500D02*
X90000D01*
G01X86900D02*
Y9000D01*
X88442Y7208D01*
X86358D01*
G01X93800Y13800D02*
Y9800D01*
X86400D01*
G01X81300Y14300D02*
Y28300D01*
G01X94300Y14300D02*
X81300D01*
G01X80200Y28300D02*
Y14300D01*
G01X67200D02*
Y28300D01*
G01X80200Y14300D02*
X67200D01*
G01X89550Y30000D02*
X89883Y30042D01*
X90175Y30208D01*
X90425Y30458D01*
X90592Y30750D01*
X90675Y31083D01*
Y31417D01*
X90592Y31750D01*
X90425Y32042D01*
X90175Y32292D01*
X89883Y32458D01*
X89550Y32500D01*
X89217Y32458D01*
X88925Y32292D01*
X88675Y32042D01*
X88508Y31750D01*
X88425Y31417D01*
Y31083D01*
X88508Y30750D01*
X88675Y30458D01*
X88925Y30208D01*
X89217Y30042D01*
X89550Y30000D01*
G01X89217Y30667D02*
X88717Y30000D01*
G01X87242Y32083D02*
X86992Y32333D01*
X86700Y32458D01*
X86367Y32500D01*
X85950Y32417D01*
X85658Y32208D01*
X85575Y31958D01*
X85617Y31708D01*
X85783Y31500D01*
X86617Y31083D01*
X86992Y30792D01*
X87242Y30375D01*
X87325Y30000D01*
X85575D01*
G01X81300Y28300D02*
X94300D01*
G01X74050Y29500D02*
X74383Y29542D01*
X74675Y29708D01*
X74925Y29958D01*
X75092Y30250D01*
X75175Y30583D01*
Y30917D01*
X75092Y31250D01*
X74925Y31542D01*
X74675Y31792D01*
X74383Y31958D01*
X74050Y32000D01*
X73717Y31958D01*
X73425Y31792D01*
X73175Y31542D01*
X73008Y31250D01*
X72925Y30917D01*
Y30583D01*
X73008Y30250D01*
X73175Y29958D01*
X73425Y29708D01*
X73717Y29542D01*
X74050Y29500D01*
G01X73717Y30167D02*
X73217Y29500D01*
G01X70950D02*
Y32000D01*
X71450Y31500D01*
G01Y29500D02*
X70450D01*
G01X67200Y28300D02*
X80200D01*
G01X62500Y29617D02*
X65000D01*
Y30658D01*
X64875Y30992D01*
X64708Y31200D01*
X64375Y31283D01*
X64042Y31200D01*
X63833Y30950D01*
X63708Y30658D01*
Y29617D01*
G01Y30658D02*
X62500Y31283D01*
G01Y33550D02*
X65000D01*
X64500Y33050D01*
G01X62500D02*
Y34050D01*
G01X120433Y4500D02*
Y7000D01*
X119392D01*
X119058Y6875D01*
X118850Y6708D01*
X118767Y6375D01*
X118850Y6042D01*
X119100Y5833D01*
X119392Y5708D01*
X120433D01*
G01X119392D02*
X118767Y4500D01*
G01X116500D02*
Y7000D01*
X117000Y6500D01*
G01Y4500D02*
X116000D01*
G01X114317Y4875D02*
X114067Y4667D01*
X113775Y4542D01*
X113400Y4500D01*
X113025Y4583D01*
X112733Y4750D01*
X112525Y5042D01*
X112483Y5375D01*
X112567Y5708D01*
X112775Y5917D01*
X113067Y6083D01*
X113358Y6125D01*
X113650Y6083D01*
X114025Y5917D01*
X113900Y7000D01*
X112775D01*
G01X120400Y12400D02*
Y8400D01*
X113000D01*
G01X132933Y4000D02*
Y6500D01*
X131892D01*
X131558Y6375D01*
X131350Y6208D01*
X131267Y5875D01*
X131350Y5542D01*
X131600Y5333D01*
X131892Y5208D01*
X132933D01*
G01X131892D02*
X131267Y4000D01*
G01X129000D02*
Y6500D01*
X129500Y6000D01*
G01Y4000D02*
X128500D01*
G01X126692Y5042D02*
X126400Y5333D01*
X126150Y5500D01*
X125817Y5583D01*
X125525Y5500D01*
X125317Y5333D01*
X125150Y5083D01*
X125108Y4792D01*
X125150Y4542D01*
X125317Y4292D01*
X125567Y4083D01*
X125858Y4000D01*
X126192Y4083D01*
X126483Y4333D01*
X126650Y4708D01*
X126692Y5125D01*
X126608Y5667D01*
X126483Y5958D01*
X126275Y6250D01*
X125983Y6458D01*
X125692Y6500D01*
X125400Y6417D01*
X125192Y6208D01*
G01X133200Y12400D02*
Y8400D01*
X125800D01*
G01X132600Y26900D02*
Y12900D01*
G01X119600D02*
Y26900D01*
G01X132600Y12900D02*
X119600D01*
G01X94300Y28300D02*
Y14300D01*
G01X118500Y26900D02*
Y12900D01*
G01X105500D02*
Y26900D01*
G01X118500Y12900D02*
X105500D01*
G01X137000Y11017D02*
X139500D01*
Y12058D01*
X139375Y12392D01*
X139208Y12600D01*
X138875Y12683D01*
X138542Y12600D01*
X138333Y12350D01*
X138208Y12058D01*
Y11017D01*
G01Y12058D02*
X137000Y12683D01*
G01Y15450D02*
X139500D01*
X137708Y13908D01*
Y15992D01*
G01X97800Y10217D02*
X100300D01*
Y11258D01*
X100175Y11592D01*
X100008Y11800D01*
X99675Y11883D01*
X99342Y11800D01*
X99133Y11550D01*
X99008Y11258D01*
Y10217D01*
G01Y11258D02*
X97800Y11883D01*
G01X99883Y13358D02*
X100133Y13608D01*
X100258Y13900D01*
X100300Y14233D01*
X100217Y14650D01*
X100008Y14942D01*
X99758Y15025D01*
X99508Y14983D01*
X99300Y14817D01*
X98883Y13983D01*
X98592Y13608D01*
X98175Y13358D01*
X97800Y13275D01*
Y15025D01*
G01X101500Y10117D02*
X104000D01*
Y11158D01*
X103875Y11492D01*
X103708Y11700D01*
X103375Y11783D01*
X103042Y11700D01*
X102833Y11450D01*
X102708Y11158D01*
Y10117D01*
G01Y11158D02*
X101500Y11783D01*
G01X102000Y13133D02*
X101708Y13383D01*
X101542Y13717D01*
X101500Y14092D01*
X101542Y14425D01*
X101750Y14758D01*
X102000Y14967D01*
X102250Y15008D01*
X102542Y14925D01*
X102750Y14633D01*
X102833Y14342D01*
Y13967D01*
G01Y14342D02*
X102958Y14592D01*
X103167Y14800D01*
X103417Y14883D01*
X103667Y14800D01*
X103875Y14592D01*
X104000Y14217D01*
X103958Y13842D01*
X103792Y13467D01*
G01X127750Y31800D02*
X128083Y31842D01*
X128375Y32008D01*
X128625Y32258D01*
X128792Y32550D01*
X128875Y32883D01*
Y33217D01*
X128792Y33550D01*
X128625Y33842D01*
X128375Y34092D01*
X128083Y34258D01*
X127750Y34300D01*
X127417Y34258D01*
X127125Y34092D01*
X126875Y33842D01*
X126708Y33550D01*
X126625Y33217D01*
Y32883D01*
X126708Y32550D01*
X126875Y32258D01*
X127125Y32008D01*
X127417Y31842D01*
X127750Y31800D01*
G01X127417Y32467D02*
X126917Y31800D01*
G01X124150D02*
Y34300D01*
X125692Y32508D01*
X123608D01*
G01X119600Y26900D02*
X132600D01*
G01X113650Y31800D02*
X113983Y31842D01*
X114275Y32008D01*
X114525Y32258D01*
X114692Y32550D01*
X114775Y32883D01*
Y33217D01*
X114692Y33550D01*
X114525Y33842D01*
X114275Y34092D01*
X113983Y34258D01*
X113650Y34300D01*
X113317Y34258D01*
X113025Y34092D01*
X112775Y33842D01*
X112608Y33550D01*
X112525Y33217D01*
Y32883D01*
X112608Y32550D01*
X112775Y32258D01*
X113025Y32008D01*
X113317Y31842D01*
X113650Y31800D01*
G01X113317Y32467D02*
X112817Y31800D01*
G01X111467Y32300D02*
X111217Y32008D01*
X110883Y31842D01*
X110508Y31800D01*
X110175Y31842D01*
X109842Y32050D01*
X109633Y32300D01*
X109592Y32550D01*
X109675Y32842D01*
X109967Y33050D01*
X110258Y33133D01*
X110633D01*
G01X110258D02*
X110008Y33258D01*
X109800Y33467D01*
X109717Y33717D01*
X109800Y33967D01*
X110008Y34175D01*
X110383Y34300D01*
X110758Y34258D01*
X111133Y34092D01*
G01X105500Y26900D02*
X118500D01*
G01X152633Y13292D02*
X152883Y13417D01*
X153175Y13500D01*
X153508D01*
X153883Y13375D01*
X154175Y13167D01*
X154383Y12917D01*
X154550Y12500D01*
X154592Y12125D01*
X154508Y11750D01*
X154383Y11500D01*
X154133Y11250D01*
X153842Y11083D01*
X153550Y11000D01*
X153258D01*
X152967Y11083D01*
X152717Y11208D01*
X152508Y11375D01*
G01X151242Y13083D02*
X150992Y13333D01*
X150700Y13458D01*
X150367Y13500D01*
X149950Y13417D01*
X149658Y13208D01*
X149575Y12958D01*
X149617Y12708D01*
X149783Y12500D01*
X150617Y12083D01*
X150992Y11792D01*
X151242Y11375D01*
X151325Y11000D01*
X149575D01*
G01X160300Y23500D02*
X154800D01*
G01X160300Y15500D02*
Y23500D01*
G01X154800Y15500D02*
X160300D01*
G01X142700D02*
X148200D01*
G01X142700Y23500D02*
Y15500D01*
G01X148200Y23500D02*
X142700D01*
G01X153633Y32292D02*
X153883Y32417D01*
X154175Y32500D01*
X154508D01*
X154883Y32375D01*
X155175Y32167D01*
X155383Y31917D01*
X155550Y31500D01*
X155592Y31125D01*
X155508Y30750D01*
X155383Y30500D01*
X155133Y30250D01*
X154842Y30083D01*
X154550Y30000D01*
X154258D01*
X153967Y30083D01*
X153717Y30208D01*
X153508Y30375D01*
G01X151450Y30000D02*
Y32500D01*
X151950Y32000D01*
G01Y30000D02*
X150950D01*
G01X213404Y30850D02*
Y35750D01*
X223054D01*
Y45850D01*
X219304D01*
Y56900D01*
X213404D01*
Y62850D01*
X173604D01*
Y56900D01*
X167704D01*
Y45850D01*
X163954D01*
Y35750D01*
X173604D01*
Y30850D01*
X213404D01*
G01X201683Y28792D02*
X201933Y28917D01*
X202225Y29000D01*
X202558D01*
X202933Y28875D01*
X203225Y28667D01*
X203433Y28417D01*
X203600Y28000D01*
X203642Y27625D01*
X203558Y27250D01*
X203433Y27000D01*
X203183Y26750D01*
X202892Y26583D01*
X202600Y26500D01*
X202308D01*
X202017Y26583D01*
X201767Y26708D01*
X201558Y26875D01*
G01X200458Y26500D02*
Y29000D01*
X198542Y26500D01*
Y29000D01*
G01X196400Y26500D02*
Y29000D01*
X196900Y28500D01*
G01Y26500D02*
X195900D01*
G01X258644Y6570D02*
Y9070D01*
X257603D01*
X257269Y8945D01*
X257061Y8778D01*
X256978Y8445D01*
X257061Y8112D01*
X257311Y7903D01*
X257603Y7778D01*
X258644D01*
G01X257603D02*
X256978Y6570D01*
G01X254711D02*
Y9070D01*
X255211Y8570D01*
G01Y6570D02*
X254211D01*
G01X251611D02*
X251319Y6612D01*
X250986Y6737D01*
X250778Y6945D01*
X250694Y7237D01*
X250778Y7528D01*
X251028Y7778D01*
X251403Y7903D01*
X251819D01*
X252069Y7987D01*
X252278Y8195D01*
X252361Y8487D01*
X252236Y8778D01*
X251944Y8987D01*
X251611Y9070D01*
X251278Y8987D01*
X250986Y8778D01*
X250861Y8487D01*
X250944Y8195D01*
X251153Y7987D01*
X251403Y7903D01*
X251819D01*
X252194Y7778D01*
X252444Y7528D01*
X252528Y7237D01*
X252444Y6945D01*
X252236Y6737D01*
X251903Y6612D01*
X251611Y6570D01*
G01X258411Y14770D02*
Y10770D01*
X251011D01*
G01X281133Y7100D02*
Y9600D01*
X280092D01*
X279758Y9475D01*
X279550Y9308D01*
X279467Y8975D01*
X279550Y8642D01*
X279800Y8433D01*
X280092Y8308D01*
X281133D01*
G01X280092D02*
X279467Y7100D01*
G01X277200D02*
Y9600D01*
X277700Y9100D01*
G01Y7100D02*
X276700D01*
G01X274183D02*
X274100Y7642D01*
X273975Y8100D01*
X273808Y8517D01*
X273600Y8975D01*
X273267Y9600D01*
X274933D01*
G01X273922Y14786D02*
Y10786D01*
X266522D01*
G01X261607Y29254D02*
Y15254D01*
G01X248607D02*
Y29254D01*
G01X261607Y15254D02*
X248607D01*
G01X275707Y29254D02*
Y15254D01*
G01X262707D02*
Y29254D01*
G01X275707Y15254D02*
X262707D01*
G01X277474Y12887D02*
X279974D01*
Y13928D01*
X279849Y14262D01*
X279682Y14470D01*
X279349Y14553D01*
X279016Y14470D01*
X278807Y14220D01*
X278682Y13928D01*
Y12887D01*
G01Y13928D02*
X277474Y14553D01*
G01X278516Y16028D02*
X278807Y16320D01*
X278974Y16570D01*
X279057Y16903D01*
X278974Y17195D01*
X278807Y17403D01*
X278557Y17570D01*
X278266Y17612D01*
X278016Y17570D01*
X277766Y17403D01*
X277557Y17153D01*
X277474Y16862D01*
X277557Y16528D01*
X277807Y16237D01*
X278182Y16070D01*
X278599Y16028D01*
X279141Y16112D01*
X279432Y16237D01*
X279724Y16445D01*
X279932Y16737D01*
X279974Y17028D01*
X279891Y17320D01*
X279682Y17528D01*
G01X239800Y23317D02*
X242300D01*
Y24358D01*
X242175Y24692D01*
X242008Y24900D01*
X241675Y24983D01*
X241342Y24900D01*
X241133Y24650D01*
X241008Y24358D01*
Y23317D01*
G01Y24358D02*
X239800Y24983D01*
G01X240175Y26333D02*
X239967Y26583D01*
X239842Y26875D01*
X239800Y27250D01*
X239883Y27625D01*
X240050Y27917D01*
X240342Y28125D01*
X240675Y28167D01*
X241008Y28083D01*
X241217Y27875D01*
X241383Y27583D01*
X241425Y27292D01*
X241383Y27000D01*
X241217Y26625D01*
X242300Y26750D01*
Y27875D01*
G01X256557Y30554D02*
X256890Y30596D01*
X257182Y30762D01*
X257432Y31012D01*
X257599Y31304D01*
X257682Y31637D01*
Y31971D01*
X257599Y32304D01*
X257432Y32596D01*
X257182Y32846D01*
X256890Y33012D01*
X256557Y33054D01*
X256224Y33012D01*
X255932Y32846D01*
X255682Y32596D01*
X255515Y32304D01*
X255432Y31971D01*
Y31637D01*
X255515Y31304D01*
X255682Y31012D01*
X255932Y30762D01*
X256224Y30596D01*
X256557Y30554D01*
G01X256224Y31221D02*
X255724Y30554D01*
G01X254249Y31596D02*
X253957Y31887D01*
X253707Y32054D01*
X253374Y32137D01*
X253082Y32054D01*
X252874Y31887D01*
X252707Y31637D01*
X252665Y31346D01*
X252707Y31096D01*
X252874Y30846D01*
X253124Y30637D01*
X253415Y30554D01*
X253749Y30637D01*
X254040Y30887D01*
X254207Y31262D01*
X254249Y31679D01*
X254165Y32221D01*
X254040Y32512D01*
X253832Y32804D01*
X253540Y33012D01*
X253249Y33054D01*
X252957Y32971D01*
X252749Y32762D01*
G01X248607Y29254D02*
X261607D01*
G01X272257Y31054D02*
X272590Y31096D01*
X272882Y31262D01*
X273132Y31512D01*
X273299Y31804D01*
X273382Y32137D01*
Y32471D01*
X273299Y32804D01*
X273132Y33096D01*
X272882Y33346D01*
X272590Y33512D01*
X272257Y33554D01*
X271924Y33512D01*
X271632Y33346D01*
X271382Y33096D01*
X271215Y32804D01*
X271132Y32471D01*
Y32137D01*
X271215Y31804D01*
X271382Y31512D01*
X271632Y31262D01*
X271924Y31096D01*
X272257Y31054D01*
G01X271924Y31721D02*
X271424Y31054D01*
G01X270074Y31429D02*
X269824Y31221D01*
X269532Y31096D01*
X269157Y31054D01*
X268782Y31137D01*
X268490Y31304D01*
X268282Y31596D01*
X268240Y31929D01*
X268324Y32262D01*
X268532Y32471D01*
X268824Y32637D01*
X269115Y32679D01*
X269407Y32637D01*
X269782Y32471D01*
X269657Y33554D01*
X268532D01*
G01X262707Y29254D02*
X275707D01*
G01X416833Y8100D02*
Y10600D01*
X415792D01*
X415458Y10475D01*
X415250Y10308D01*
X415167Y9975D01*
X415250Y9642D01*
X415500Y9433D01*
X415792Y9308D01*
X416833D01*
G01X415792D02*
X415167Y8100D01*
G01X412900D02*
Y10600D01*
X413400Y10100D01*
G01Y8100D02*
X412400D01*
G01X410508Y8392D02*
X410217Y8183D01*
X409883Y8100D01*
X409550Y8183D01*
X409258Y8433D01*
X409050Y8808D01*
X408967Y9183D01*
Y9642D01*
X409050Y10017D01*
X409258Y10350D01*
X409508Y10517D01*
X409800Y10600D01*
X410133Y10517D01*
X410383Y10350D01*
X410550Y10100D01*
X410633Y9767D01*
X410550Y9475D01*
X410342Y9183D01*
X410092Y9017D01*
X409800Y8975D01*
X409467Y9058D01*
X409217Y9267D01*
X408967Y9642D01*
G01X423500Y15800D02*
Y11800D01*
X416100D01*
G01X412400Y16300D02*
Y30300D01*
G01X425400Y16300D02*
X412400D01*
G01X402500Y24117D02*
X405000D01*
Y25158D01*
X404875Y25492D01*
X404708Y25700D01*
X404375Y25783D01*
X404042Y25700D01*
X403833Y25450D01*
X403708Y25158D01*
Y24117D01*
G01Y25158D02*
X402500Y25783D01*
G01Y27967D02*
X403042Y28050D01*
X403500Y28175D01*
X403917Y28342D01*
X404375Y28550D01*
X405000Y28883D01*
Y27217D01*
G01X420550Y32000D02*
X420883Y32042D01*
X421175Y32208D01*
X421425Y32458D01*
X421592Y32750D01*
X421675Y33083D01*
Y33417D01*
X421592Y33750D01*
X421425Y34042D01*
X421175Y34292D01*
X420883Y34458D01*
X420550Y34500D01*
X420217Y34458D01*
X419925Y34292D01*
X419675Y34042D01*
X419508Y33750D01*
X419425Y33417D01*
Y33083D01*
X419508Y32750D01*
X419675Y32458D01*
X419925Y32208D01*
X420217Y32042D01*
X420550Y32000D01*
G01X420217Y32667D02*
X419717Y32000D01*
G01X417533D02*
X417450Y32542D01*
X417325Y33000D01*
X417158Y33417D01*
X416950Y33875D01*
X416617Y34500D01*
X418283D01*
G01X412400Y30300D02*
X425400D01*
G01X432233Y8300D02*
Y10800D01*
X431192D01*
X430858Y10675D01*
X430650Y10508D01*
X430567Y10175D01*
X430650Y9842D01*
X430900Y9633D01*
X431192Y9508D01*
X432233D01*
G01X431192D02*
X430567Y8300D01*
G01X429092Y10383D02*
X428842Y10633D01*
X428550Y10758D01*
X428217Y10800D01*
X427800Y10717D01*
X427508Y10508D01*
X427425Y10258D01*
X427467Y10008D01*
X427633Y9800D01*
X428467Y9383D01*
X428842Y9092D01*
X429092Y8675D01*
X429175Y8300D01*
X427425D01*
G01X425200Y10800D02*
X425533Y10717D01*
X425783Y10508D01*
X425950Y10258D01*
X426075Y9925D01*
X426117Y9550D01*
X426075Y9175D01*
X425950Y8842D01*
X425783Y8592D01*
X425533Y8383D01*
X425200Y8300D01*
X424867Y8383D01*
X424617Y8592D01*
X424450Y8842D01*
X424325Y9175D01*
X424283Y9550D01*
X424325Y9925D01*
X424450Y10258D01*
X424617Y10508D01*
X424867Y10717D01*
X425200Y10800D01*
G01X437600Y15800D02*
Y11800D01*
X430200D01*
G01X439600Y30300D02*
Y16300D01*
G01X426600D02*
Y30300D01*
G01X439600Y16300D02*
X426600D01*
G01X425400Y30300D02*
Y16300D01*
G01X441000Y12617D02*
X443500D01*
Y13658D01*
X443375Y13992D01*
X443208Y14200D01*
X442875Y14283D01*
X442542Y14200D01*
X442333Y13950D01*
X442208Y13658D01*
Y12617D01*
G01Y13658D02*
X441000Y14283D01*
G01Y16550D02*
X441042Y16842D01*
X441167Y17175D01*
X441375Y17383D01*
X441667Y17467D01*
X441958Y17383D01*
X442208Y17133D01*
X442333Y16758D01*
Y16342D01*
X442417Y16092D01*
X442625Y15883D01*
X442917Y15800D01*
X443208Y15925D01*
X443417Y16217D01*
X443500Y16550D01*
X443417Y16883D01*
X443208Y17175D01*
X442917Y17300D01*
X442625Y17217D01*
X442417Y17008D01*
X442333Y16758D01*
Y16342D01*
X442208Y15967D01*
X441958Y15717D01*
X441667Y15633D01*
X441375Y15717D01*
X441167Y15925D01*
X441042Y16258D01*
X441000Y16550D01*
G01X434550Y32000D02*
X434883Y32042D01*
X435175Y32208D01*
X435425Y32458D01*
X435592Y32750D01*
X435675Y33083D01*
Y33417D01*
X435592Y33750D01*
X435425Y34042D01*
X435175Y34292D01*
X434883Y34458D01*
X434550Y34500D01*
X434217Y34458D01*
X433925Y34292D01*
X433675Y34042D01*
X433508Y33750D01*
X433425Y33417D01*
Y33083D01*
X433508Y32750D01*
X433675Y32458D01*
X433925Y32208D01*
X434217Y32042D01*
X434550Y32000D01*
G01X434217Y32667D02*
X433717Y32000D01*
G01X431450D02*
X431158Y32042D01*
X430825Y32167D01*
X430617Y32375D01*
X430533Y32667D01*
X430617Y32958D01*
X430867Y33208D01*
X431242Y33333D01*
X431658D01*
X431908Y33417D01*
X432117Y33625D01*
X432200Y33917D01*
X432075Y34208D01*
X431783Y34417D01*
X431450Y34500D01*
X431117Y34417D01*
X430825Y34208D01*
X430700Y33917D01*
X430783Y33625D01*
X430992Y33417D01*
X431242Y33333D01*
X431658D01*
X432033Y33208D01*
X432283Y32958D01*
X432367Y32667D01*
X432283Y32375D01*
X432075Y32167D01*
X431742Y32042D01*
X431450Y32000D01*
G01X426600Y30300D02*
X439600D01*
G01X557533Y7500D02*
Y10000D01*
X556492D01*
X556158Y9875D01*
X555950Y9708D01*
X555867Y9375D01*
X555950Y9042D01*
X556200Y8833D01*
X556492Y8708D01*
X557533D01*
G01X556492D02*
X555867Y7500D01*
G01X554392Y9583D02*
X554142Y9833D01*
X553850Y9958D01*
X553517Y10000D01*
X553100Y9917D01*
X552808Y9708D01*
X552725Y9458D01*
X552767Y9208D01*
X552933Y9000D01*
X553767Y8583D01*
X554142Y8292D01*
X554392Y7875D01*
X554475Y7500D01*
X552725D01*
G01X551292Y9583D02*
X551042Y9833D01*
X550750Y9958D01*
X550417Y10000D01*
X550000Y9917D01*
X549708Y9708D01*
X549625Y9458D01*
X549667Y9208D01*
X549833Y9000D01*
X550667Y8583D01*
X551042Y8292D01*
X551292Y7875D01*
X551375Y7500D01*
X549625D01*
G01X563700Y15000D02*
Y11000D01*
X556300D01*
G01X544833Y7400D02*
Y9900D01*
X543792D01*
X543458Y9775D01*
X543250Y9608D01*
X543167Y9275D01*
X543250Y8942D01*
X543500Y8733D01*
X543792Y8608D01*
X544833D01*
G01X543792D02*
X543167Y7400D01*
G01X541692Y9483D02*
X541442Y9733D01*
X541150Y9858D01*
X540817Y9900D01*
X540400Y9817D01*
X540108Y9608D01*
X540025Y9358D01*
X540067Y9108D01*
X540233Y8900D01*
X541067Y8483D01*
X541442Y8192D01*
X541692Y7775D01*
X541775Y7400D01*
X540025D01*
G01X537800D02*
Y9900D01*
X538300Y9400D01*
G01Y7400D02*
X537300D01*
G01X550200Y15000D02*
Y11000D01*
X542800D01*
G01X565800Y29500D02*
Y15500D01*
G01X552800D02*
Y29500D01*
G01X565800Y15500D02*
X552800D01*
G01X551600Y29500D02*
Y15500D01*
G01X538600D02*
Y29500D01*
G01X551600Y15500D02*
X538600D01*
G01X529000Y22617D02*
X531500D01*
Y23658D01*
X531375Y23992D01*
X531208Y24200D01*
X530875Y24283D01*
X530542Y24200D01*
X530333Y23950D01*
X530208Y23658D01*
Y22617D01*
G01Y23658D02*
X529000Y24283D01*
G01X529292Y25842D02*
X529083Y26133D01*
X529000Y26467D01*
X529083Y26800D01*
X529333Y27092D01*
X529708Y27300D01*
X530083Y27383D01*
X530542D01*
X530917Y27300D01*
X531250Y27092D01*
X531417Y26842D01*
X531500Y26550D01*
X531417Y26217D01*
X531250Y25967D01*
X531000Y25800D01*
X530667Y25717D01*
X530375Y25800D01*
X530083Y26008D01*
X529917Y26258D01*
X529875Y26550D01*
X529958Y26883D01*
X530167Y27133D01*
X530542Y27383D01*
G01X567500Y8567D02*
X570000D01*
Y9608D01*
X569875Y9942D01*
X569708Y10150D01*
X569375Y10233D01*
X569042Y10150D01*
X568833Y9900D01*
X568708Y9608D01*
Y8567D01*
G01Y9608D02*
X567500Y10233D01*
G01Y12500D02*
X570000D01*
X569500Y12000D01*
G01X567500D02*
Y13000D01*
G01X570000Y15600D02*
X569917Y15267D01*
X569708Y15017D01*
X569458Y14850D01*
X569125Y14725D01*
X568750Y14683D01*
X568375Y14725D01*
X568042Y14850D01*
X567792Y15017D01*
X567583Y15267D01*
X567500Y15600D01*
X567583Y15933D01*
X567792Y16183D01*
X568042Y16350D01*
X568375Y16475D01*
X568750Y16517D01*
X569125Y16475D01*
X569458Y16350D01*
X569708Y16183D01*
X569917Y15933D01*
X570000Y15600D01*
G01X562100Y31000D02*
X562433Y31042D01*
X562725Y31208D01*
X562975Y31458D01*
X563142Y31750D01*
X563225Y32083D01*
Y32417D01*
X563142Y32750D01*
X562975Y33042D01*
X562725Y33292D01*
X562433Y33458D01*
X562100Y33500D01*
X561767Y33458D01*
X561475Y33292D01*
X561225Y33042D01*
X561058Y32750D01*
X560975Y32417D01*
Y32083D01*
X561058Y31750D01*
X561225Y31458D01*
X561475Y31208D01*
X561767Y31042D01*
X562100Y31000D01*
G01X561767Y31667D02*
X561267Y31000D01*
G01X559000D02*
Y33500D01*
X559500Y33000D01*
G01Y31000D02*
X558500D01*
G01X555900Y33500D02*
X556233Y33417D01*
X556483Y33208D01*
X556650Y32958D01*
X556775Y32625D01*
X556817Y32250D01*
X556775Y31875D01*
X556650Y31542D01*
X556483Y31292D01*
X556233Y31083D01*
X555900Y31000D01*
X555567Y31083D01*
X555317Y31292D01*
X555150Y31542D01*
X555025Y31875D01*
X554983Y32250D01*
X555025Y32625D01*
X555150Y32958D01*
X555317Y33208D01*
X555567Y33417D01*
X555900Y33500D01*
G01X552800Y29500D02*
X565800D01*
G01X546550Y31500D02*
X546883Y31542D01*
X547175Y31708D01*
X547425Y31958D01*
X547592Y32250D01*
X547675Y32583D01*
Y32917D01*
X547592Y33250D01*
X547425Y33542D01*
X547175Y33792D01*
X546883Y33958D01*
X546550Y34000D01*
X546217Y33958D01*
X545925Y33792D01*
X545675Y33542D01*
X545508Y33250D01*
X545425Y32917D01*
Y32583D01*
X545508Y32250D01*
X545675Y31958D01*
X545925Y31708D01*
X546217Y31542D01*
X546550Y31500D01*
G01X546217Y32167D02*
X545717Y31500D01*
G01X544158Y31792D02*
X543867Y31583D01*
X543533Y31500D01*
X543200Y31583D01*
X542908Y31833D01*
X542700Y32208D01*
X542617Y32583D01*
Y33042D01*
X542700Y33417D01*
X542908Y33750D01*
X543158Y33917D01*
X543450Y34000D01*
X543783Y33917D01*
X544033Y33750D01*
X544200Y33500D01*
X544283Y33167D01*
X544200Y32875D01*
X543992Y32583D01*
X543742Y32417D01*
X543450Y32375D01*
X543117Y32458D01*
X542867Y32667D01*
X542617Y33042D01*
G01X538600Y29500D02*
X551600D01*
G01X650733Y6800D02*
Y9300D01*
X649692D01*
X649358Y9175D01*
X649150Y9008D01*
X649067Y8675D01*
X649150Y8342D01*
X649400Y8133D01*
X649692Y8008D01*
X650733D01*
G01X649692D02*
X649067Y6800D01*
G01X647592Y8883D02*
X647342Y9133D01*
X647050Y9258D01*
X646717Y9300D01*
X646300Y9217D01*
X646008Y9008D01*
X645925Y8758D01*
X645967Y8508D01*
X646133Y8300D01*
X646967Y7883D01*
X647342Y7592D01*
X647592Y7175D01*
X647675Y6800D01*
X645925D01*
G01X643200D02*
Y9300D01*
X644742Y7508D01*
X642658D01*
G01X657100Y14500D02*
Y10500D01*
X649700D01*
G01X635433Y6700D02*
Y9200D01*
X634392D01*
X634058Y9075D01*
X633850Y8908D01*
X633767Y8575D01*
X633850Y8242D01*
X634100Y8033D01*
X634392Y7908D01*
X635433D01*
G01X634392D02*
X633767Y6700D01*
G01X632292Y8783D02*
X632042Y9033D01*
X631750Y9158D01*
X631417Y9200D01*
X631000Y9117D01*
X630708Y8908D01*
X630625Y8658D01*
X630667Y8408D01*
X630833Y8200D01*
X631667Y7783D01*
X632042Y7492D01*
X632292Y7075D01*
X632375Y6700D01*
X630625D01*
G01X629317Y7200D02*
X629067Y6908D01*
X628733Y6742D01*
X628358Y6700D01*
X628025Y6742D01*
X627692Y6950D01*
X627483Y7200D01*
X627442Y7450D01*
X627525Y7742D01*
X627817Y7950D01*
X628108Y8033D01*
X628483D01*
G01X628108D02*
X627858Y8158D01*
X627650Y8367D01*
X627567Y8617D01*
X627650Y8867D01*
X627858Y9075D01*
X628233Y9200D01*
X628608Y9158D01*
X628983Y8992D01*
G01X642000Y14300D02*
Y10300D01*
X634600D01*
G01X658200Y29000D02*
Y15000D01*
G01X645200D02*
Y29000D01*
G01X658200Y15000D02*
X645200D01*
G01X644000Y29000D02*
Y15000D01*
G01X631000D02*
Y29000D01*
G01X644000Y15000D02*
X631000D01*
G01X621000Y23067D02*
X623500D01*
Y24108D01*
X623375Y24442D01*
X623208Y24650D01*
X622875Y24733D01*
X622542Y24650D01*
X622333Y24400D01*
X622208Y24108D01*
Y23067D01*
G01Y24108D02*
X621000Y24733D01*
G01Y27000D02*
X623500D01*
X623000Y26500D01*
G01X621000D02*
Y27500D01*
G01Y30100D02*
X623500D01*
X623000Y29600D01*
G01X621000D02*
Y30600D01*
G01X655100Y30500D02*
X655433Y30542D01*
X655725Y30708D01*
X655975Y30958D01*
X656142Y31250D01*
X656225Y31583D01*
Y31917D01*
X656142Y32250D01*
X655975Y32542D01*
X655725Y32792D01*
X655433Y32958D01*
X655100Y33000D01*
X654767Y32958D01*
X654475Y32792D01*
X654225Y32542D01*
X654058Y32250D01*
X653975Y31917D01*
Y31583D01*
X654058Y31250D01*
X654225Y30958D01*
X654475Y30708D01*
X654767Y30542D01*
X655100Y30500D01*
G01X654767Y31167D02*
X654267Y30500D01*
G01X652000D02*
Y33000D01*
X652500Y32500D01*
G01Y30500D02*
X651500D01*
G01X649692Y32583D02*
X649442Y32833D01*
X649150Y32958D01*
X648817Y33000D01*
X648400Y32917D01*
X648108Y32708D01*
X648025Y32458D01*
X648067Y32208D01*
X648233Y32000D01*
X649067Y31583D01*
X649442Y31292D01*
X649692Y30875D01*
X649775Y30500D01*
X648025D01*
G01X645200Y29000D02*
X658200D01*
G01X641100Y30500D02*
X641433Y30542D01*
X641725Y30708D01*
X641975Y30958D01*
X642142Y31250D01*
X642225Y31583D01*
Y31917D01*
X642142Y32250D01*
X641975Y32542D01*
X641725Y32792D01*
X641433Y32958D01*
X641100Y33000D01*
X640767Y32958D01*
X640475Y32792D01*
X640225Y32542D01*
X640058Y32250D01*
X639975Y31917D01*
Y31583D01*
X640058Y31250D01*
X640225Y30958D01*
X640475Y30708D01*
X640767Y30542D01*
X641100Y30500D01*
G01X640767Y31167D02*
X640267Y30500D01*
G01X638000D02*
Y33000D01*
X638500Y32500D01*
G01Y30500D02*
X637500D01*
G01X634900D02*
Y33000D01*
X635400Y32500D01*
G01Y30500D02*
X634400D01*
G01X631000Y29000D02*
X644000D01*
G01X662000Y28567D02*
X664500D01*
Y29608D01*
X664375Y29942D01*
X664208Y30150D01*
X663875Y30233D01*
X663542Y30150D01*
X663333Y29900D01*
X663208Y29608D01*
Y28567D01*
G01Y29608D02*
X662000Y30233D01*
G01Y32500D02*
X664500D01*
X664000Y32000D01*
G01X662000D02*
Y33000D01*
G01X664083Y34808D02*
X664333Y35058D01*
X664458Y35350D01*
X664500Y35683D01*
X664417Y36100D01*
X664208Y36392D01*
X663958Y36475D01*
X663708Y36433D01*
X663500Y36267D01*
X663083Y35433D01*
X662792Y35058D01*
X662375Y34808D01*
X662000Y34725D01*
Y36475D01*
G54D14*
G01X65100Y22900D02*
X66200D01*
G01X62400D02*
X63500D01*
G01X136300Y22000D02*
X137400D01*
G01X133600D02*
X134700D01*
G01X98000Y23400D02*
X99100D01*
G01X95300D02*
X96400D01*
G01X103400D02*
X104500D01*
G01X100700D02*
X101800D01*
G01X152500Y28300D02*
Y24300D01*
G01X279374Y23870D02*
X280474D01*
G01X276674D02*
X277774D01*
G01X246553Y24417D02*
X247653D01*
G01X243853D02*
X244953D01*
G01X410200Y23700D02*
X411300D01*
G01X407500D02*
X408600D01*
G01X443300D02*
X444400D01*
G01X440600D02*
X441700D01*
G01X536500Y23300D02*
X537600D01*
G01X533800D02*
X534900D01*
G01X569600Y23200D02*
X570700D01*
G01X566900D02*
X568000D01*
G01X628800Y22600D02*
X629900D01*
G01X626100D02*
X627200D01*
G01X661900Y22700D02*
X663000D01*
G01X659200D02*
X660300D01*
M02*
